# T6G (Grand Teton) — schematic netlist excerpt (pin names and nets, part order shuffled) for the footprints in the layout excerpt that follows; sources: Cadence DE-HDL packaged netlist, KiCad conversion of 04192023_DAF0TMB3IC0_F0TG_MB_C_brd_V02_OCP.brd

H44  HOLE  EMPTY  pkg TH  page 230 : \1\ = GND
C1861  Q_CAP  0.1UF 25V 10% X7R  pkg 0402  page 247 : A = P3V3_OCP_V3_2 ; B = GND
R4146  Q_RES  33.2 1% CHIP  pkg 0402LF  page 80 : A = GPU_3V3IO_RSVD3_FFU_ISO_R ; B = GPU_3V3IO_RSVD3_FFU_ISO

(kicad_pcb
	(version 20260206)
	(generator "pcbnew")
	(generator_version "10.0")
	(general
		(thickness 1.6)
		(legacy_teardrops no)
	)
	(paper "A4")
	(title_block
		(title "04192023_DAF0TMB3IC0_F0TG_MB_C_brd_V02_OCP.brd")
		(comment 1 "Grand Teton / footprints 1758-1760 of 8354")
	)
	(layers
		(0 "F.Cu" signal "TOP")
		(4 "In1.Cu" signal "GND")
		(6 "In2.Cu" signal "IN1")
		(8 "In3.Cu" signal "GND1")
		(10 "In4.Cu" signal "IN2")
		(12 "In5.Cu" signal "GND2")
		(14 "In6.Cu" signal "IN3")
		(16 "In7.Cu" signal "GND3")
		(18 "In8.Cu" signal "VCC")
		(20 "In9.Cu" signal "VCC1")
		(22 "In10.Cu" signal "GND4")
		(24 "In11.Cu" signal "IN4")
		(26 "In12.Cu" signal "GND5")
		(28 "In13.Cu" signal "IN5")
		(30 "In14.Cu" signal "GND6")
		(32 "In15.Cu" signal "IN6")
		(34 "In16.Cu" signal "GND7")
		(2 "B.Cu" signal "BOTTOM")
		(9 "F.Adhes" user "F.Adhesive")
		(11 "B.Adhes" user "B.Adhesive")
		(13 "F.Paste" user "Package Geometry/Pastemask Top")
		(15 "B.Paste" user "Package Geometry/Pastemask Bottom")
		(5 "F.SilkS" user "Ref Des/Silkscreen Top")
		(7 "B.SilkS" user "Ref Des/Silkscreen Bottom")
		(1 "F.Mask" user "Board Geometry/Soldermask Top")
		(3 "B.Mask" user "Board Geometry/Soldermask Bottom")
		(17 "Dwgs.User" user "User.Drawings")
		(19 "Cmts.User" user "User.Comments")
		(21 "Eco1.User" user "User.Eco1")
		(23 "Eco2.User" user "User.Eco2")
		(25 "Edge.Cuts" user "Board Geometry/Outline")
		(27 "Margin" user)
		(31 "F.CrtYd" user "Package Geometry/Place Bound Top")
		(29 "B.CrtYd" user "Package Geometry/Place Bound Bottom")
		(35 "F.Fab" user "Ref Des/Assembly Top")
		(33 "B.Fab" user "Ref Des/Assembly Bottom")
	)
	(footprint ""
		(layer "F.Cu")
		(at 205.243684 -121.960386)
		(property "Reference" "R4146"
			(at 0 0 0)
			(layer "F.SilkS")
			(hide yes)
			(effects
				(font
					(size 1.27 1.27)
				)
			)
		)
		(property "Value" ""
			(at 0 0 0)
			(layer "F.Fab")
			(effects
				(font
					(size 1.27 1.27)
				)
			)
		)
		(duplicate_pad_numbers_are_jumpers no)
		(fp_line
			(start -0.7874 -0.4064)
			(end 0.7874 -0.4064)
			(stroke
				(width 0.1524)
				(type default)
			)
			(layer "F.SilkS")
		)
		(fp_line
			(start -0.7874 0.4064)
			(end -0.7874 -0.4064)
			(stroke
				(width 0.1524)
				(type default)
			)
			(layer "F.SilkS")
		)
		(fp_line
			(start 0.7874 -0.4064)
			(end 0.7874 0.4064)
			(stroke
				(width 0.1524)
				(type default)
			)
			(layer "F.SilkS")
		)
		(fp_line
			(start 0.7874 0.4064)
			(end -0.7874 0.4064)
			(stroke
				(width 0.1524)
				(type default)
			)
			(layer "F.SilkS")
		)
		(fp_line
			(start -0.67945 -0.305054)
			(end -0.12065 -0.305054)
			(stroke
				(width 0.1)
				(type default)
			)
			(layer "F.Fab")
		)
		(fp_line
			(start -0.67945 0.3048)
			(end -0.67945 -0.305054)
			(stroke
				(width 0.1)
				(type default)
			)
			(layer "F.Fab")
		)
		(fp_line
			(start -0.12065 -0.305054)
			(end -0.12065 -0.2794)
			(stroke
				(width 0.1)
				(type default)
			)
			(layer "F.Fab")
		)
		(fp_line
			(start -0.12065 -0.2794)
			(end 0.12065 -0.2794)
			(stroke
				(width 0.1)
				(type default)
			)
			(layer "F.Fab")
		)
		(fp_line
			(start -0.12065 0.2794)
			(end -0.12065 0.3048)
			(stroke
				(width 0.1)
				(type default)
			)
			(layer "F.Fab")
		)
		(fp_line
			(start -0.12065 0.3048)
			(end -0.67945 0.3048)
			(stroke
				(width 0.1)
				(type default)
			)
			(layer "F.Fab")
		)
		(fp_line
			(start 0.120396 0.2794)
			(end -0.12065 0.2794)
			(stroke
				(width 0.1)
				(type default)
			)
			(layer "F.Fab")
		)
		(fp_line
			(start 0.120396 0.3048)
			(end 0.120396 0.2794)
			(stroke
				(width 0.1)
				(type default)
			)
			(layer "F.Fab")
		)
		(fp_line
			(start 0.12065 -0.3048)
			(end 0.67945 -0.3048)
			(stroke
				(width 0.1)
				(type default)
			)
			(layer "F.Fab")
		)
		(fp_line
			(start 0.12065 -0.2794)
			(end 0.12065 -0.3048)
			(stroke
				(width 0.1)
				(type default)
			)
			(layer "F.Fab")
		)
		(fp_line
			(start 0.67945 -0.3048)
			(end 0.67945 0.3048)
			(stroke
				(width 0.1)
				(type default)
			)
			(layer "F.Fab")
		)
		(fp_line
			(start 0.67945 0.3048)
			(end 0.120396 0.3048)
			(stroke
				(width 0.1)
				(type default)
			)
			(layer "F.Fab")
		)
		(pad "1" smd circle
			(at -0.40005 0)
			(size 0 0)
			(layers "F.Cu" "F.Mask" "F.Paste")
			(net "GPU_3V3IO_RSVD3_FFU_ISO_R")
		)
		(pad "2" smd circle
			(at 0.40005 0)
			(size 0 0)
			(layers "F.Cu" "F.Mask" "F.Paste")
			(net "GPU_3V3IO_RSVD3_FFU_ISO")
		)
	)
	(footprint ""
		(layer "F.Cu")
		(at 151.19604 -40.403526 90)
		(property "Reference" "C1861"
			(at 0 0 90)
			(layer "F.SilkS")
			(hide yes)
			(effects
				(font
					(size 1.27 1.27)
				)
			)
		)
		(property "Value" ""
			(at 0 0 90)
			(layer "F.Fab")
			(effects
				(font
					(size 1.27 1.27)
				)
			)
		)
		(duplicate_pad_numbers_are_jumpers no)
		(fp_line
			(start 0.7874 -0.4064)
			(end 0.7874 0.4064)
			(stroke
				(width 0.1524)
				(type default)
			)
			(layer "F.SilkS")
		)
		(fp_line
			(start -0.7874 -0.4064)
			(end 0.7874 -0.4064)
			(stroke
				(width 0.1524)
				(type default)
			)
			(layer "F.SilkS")
		)
		(fp_line
			(start 0.7874 0.4064)
			(end -0.7874 0.4064)
			(stroke
				(width 0.1524)
				(type default)
			)
			(layer "F.SilkS")
		)
		(fp_line
			(start -0.7874 0.4064)
			(end -0.7874 -0.4064)
			(stroke
				(width 0.1524)
				(type default)
			)
			(layer "F.SilkS")
		)
		(fp_line
			(start -0.12065 -0.305054)
			(end -0.12065 -0.2794)
			(stroke
				(width 0.1)
				(type default)
			)
			(layer "F.Fab")
		)
		(fp_line
			(start -0.67945 -0.305054)
			(end -0.12065 -0.305054)
			(stroke
				(width 0.1)
				(type default)
			)
			(layer "F.Fab")
		)
		(fp_line
			(start 0.67945 -0.3048)
			(end 0.67945 0.3048)
			(stroke
				(width 0.1)
				(type default)
			)
			(layer "F.Fab")
		)
		(fp_line
			(start 0.12065 -0.3048)
			(end 0.67945 -0.3048)
			(stroke
				(width 0.1)
				(type default)
			)
			(layer "F.Fab")
		)
		(fp_line
			(start 0.12065 -0.2794)
			(end 0.12065 -0.3048)
			(stroke
				(width 0.1)
				(type default)
			)
			(layer "F.Fab")
		)
		(fp_line
			(start -0.12065 -0.2794)
			(end 0.12065 -0.2794)
			(stroke
				(width 0.1)
				(type default)
			)
			(layer "F.Fab")
		)
		(fp_line
			(start 0.120396 0.2794)
			(end -0.12065 0.2794)
			(stroke
				(width 0.1)
				(type default)
			)
			(layer "F.Fab")
		)
		(fp_line
			(start -0.12065 0.2794)
			(end -0.12065 0.3048)
			(stroke
				(width 0.1)
				(type default)
			)
			(layer "F.Fab")
		)
		(fp_line
			(start 0.67945 0.3048)
			(end 0.120396 0.3048)
			(stroke
				(width 0.1)
				(type default)
			)
			(layer "F.Fab")
		)
		(fp_line
			(start 0.120396 0.3048)
			(end 0.120396 0.2794)
			(stroke
				(width 0.1)
				(type default)
			)
			(layer "F.Fab")
		)
		(fp_line
			(start -0.12065 0.3048)
			(end -0.67945 0.3048)
			(stroke
				(width 0.1)
				(type default)
			)
			(layer "F.Fab")
		)
		(fp_line
			(start -0.67945 0.3048)
			(end -0.67945 -0.305054)
			(stroke
				(width 0.1)
				(type default)
			)
			(layer "F.Fab")
		)
		(pad "1" smd circle
			(at -0.40005 0 90)
			(size 0 0)
			(layers "F.Cu" "F.Mask" "F.Paste")
			(net "P3V3_OCP_V3_2")
		)
		(pad "2" smd circle
			(at 0.40005 0 90)
			(size 0 0)
			(layers "F.Cu" "F.Mask" "F.Paste")
			(net "GND")
		)
	)
	(footprint ""
		(layer "F.Cu")
		(at 359.952036 -340.315042)
		(property "Reference" "H44"
			(at -0.528574 -5.339334 0)
			(unlocked yes)
			(layer "F.SilkS")
			(effects
				(font
					(size 0.7874 0.5842)
					(thickness 0.1524)
				)
				(justify left)
			)
		)
		(property "Value" ""
			(at 0 0 0)
			(layer "F.Fab")
			(effects
				(font
					(size 1.27 1.27)
				)
			)
		)
		(duplicate_pad_numbers_are_jumpers no)
		(pad "1" thru_hole circle
			(at 0 0)
			(size 6.1976 6.1976)
			(drill 3.7338)
			(layers "*.Cu" "*.Mask")
			(remove_unused_layers no)
			(net "GND")
			(clearance -0.9779)
			(padstack
				(mode front_inner_back)
				(layer "Inner"
					(shape circle)
					(size 5.5372 5.5372)
					(clearance -0.6477)
				)
				(layer "B.Cu"
					(shape circle)
					(size 6.1976 6.1976)
					(clearance -0.9779)
				)
			)
		)
	)
)
